#ISCELL
  mstr_misc dns *
  *
#ISCELL
  mstr_symbols bom_note *
  *
#ISCELL
  mstr_symbols design_note *
  *
#ISCELL
  mstr_symbols intel_corp_bpage *
  *
#ISCELL
  mstr_standard offpage *
  page189_i1
#ISCELL
  mstr_standard offpage *
  page189_i10
#ISCELL
  mstr_standard offpage *
  page189_i11
#ISCELL
  mstr_standard offpage *
  page189_i12
#CELL
  mstr_discrete res *
  page189_i13
#ISCELL
  mstr_standard offpage *
  page189_i14
#ISCELL
  mstr_standard offpage *
  page189_i15
#ISCELL
  mstr_standard offpage *
  page189_i16
#CELL
  mstr_discrete res *
  page189_i17
#CELL
  mstr_discrete res *
  page189_i18
#CELL
  mstr_discrete res *
  page189_i19
#ISCELL
  mstr_standard offpage *
  page189_i2
#CELL
  mstr_discrete res *
  page189_i20
#CELL
  mstr_discrete res *
  page189_i21
#CELL
  mstr_discrete res *
  page189_i22
#CELL
  mstr_discrete res *
  page189_i23
#CELL
  mstr_discrete res *
  page189_i24
#CELL
  mstr_discrete res *
  page189_i25
#CELL
  mstr_discrete res *
  page189_i26
#CELL
  mstr_discrete res *
  page189_i27
#ISCELL
  mstr_standard offpage *
  page189_i28
#ISCELL
  mstr_standard offpage *
  page189_i29
#ISCELL
  mstr_standard offpage *
  page189_i3
#ISCELL
  mstr_standard offpage *
  page189_i30
#ISCELL
  mstr_standard offpage *
  page189_i31
#ISCELL
  mstr_standard offpage *
  page189_i32
#ISCELL
  mstr_standard offpage *
  page189_i33
#ISCELL
  mstr_standard offpage *
  page189_i34
#ISCELL
  mstr_standard offpage *
  page189_i35
#CELL
  mstr_discrete res *
  page189_i36
#CELL
  mstr_discrete res *
  page189_i37
#CELL
  mstr_discrete res *
  page189_i38
#ISCELL
  mstr_standard offpage *
  page189_i39
#ISCELL
  mstr_standard offpage *
  page189_i4
#ISCELL
  mstr_standard offpage *
  page189_i40
#ISCELL
  mstr_standard offpage *
  page189_i41
#ISCELL
  mstr_standard offpage *
  page189_i42
#ISCELL
  mstr_symbols p3v3_stby *
  page189_i43
#CELL
  mstr_discrete res *
  page189_i44
#CELL
  mstr_discrete res *
  page189_i45
#ISCELL
  mstr_symbols gnd *
  page189_i46
#CELL
  mstr_conn conn8_c77962004 *
  page189_i47
#ISCELL
  mstr_symbols p3v3_stby *
  page189_i48
#CELL
  mstr_discrete diode *
  page189_i49
#ISCELL
  mstr_standard offpage *
  page189_i5
#CELL
  mstr_discrete res *
  page189_i50
#CELL
  mstr_discrete res *
  page189_i51
#ISCELL
  mstr_symbols p3v3_stby *
  page189_i52
#CELL
  mstr_discrete res *
  page189_i53
#ISCELL
  mstr_symbols gnd *
  page189_i54
#ISCELL
  mstr_symbols gnd *
  page189_i55
#CELL
  mstr_discrete res *
  page189_i56
#ISCELL
  mstr_standard offpage *
  page189_i57
#ISCELL
  mstr_standard offpage *
  page189_i58
#ISCELL
  mstr_standard offpage *
  page189_i59
#ISCELL
  mstr_standard offpage *
  page189_i6
#ISCELL
  mstr_standard offpage *
  page189_i60
#ISCELL
  mstr_standard offpage *
  page189_i61
#ISCELL
  mstr_standard offpage *
  page189_i62
#CELL
  mstr_discrete res *
  page189_i63
#CELL
  mstr_discrete res *
  page189_i64
#CELL
  mstr_discrete res *
  page189_i65
#CELL
  mstr_discrete res *
  page189_i66
#CELL
  mstr_ttl ttl3126 *
  page189_i67
#ISCELL
  mstr_symbols p3v3_stby *
  page189_i68
#CELL
  mstr_discrete cap *
  page189_i69
#CELL
  mstr_discrete res *
  page189_i7
#ISCELL
  mstr_symbols gnd *
  page189_i70
#ISCELL
  mstr_standard offpage *
  page189_i71
#ISCELL
  mstr_standard offpage *
  page189_i72
#ISCELL
  mstr_standard offpage *
  page189_i73
#ISCELL
  mstr_standard offpage *
  page189_i74
#ISCELL
  mstr_standard offpage *
  page189_i75
#CELL
  mstr_discrete res *
  page189_i76
#CELL
  mstr_discrete res *
  page189_i77
#ISCELL
  mstr_standard offpage *
  page189_i78
#ISCELL
  mstr_standard offpage *
  page189_i79
#CELL
  mstr_discrete res *
  page189_i8
#ISCELL
  mstr_standard offpage *
  page189_i80
#CELL
  mstr_discrete res *
  page189_i9
